# BASEBOARD_FAB2 (Tioga Pass) — schematic netlist excerpt (pin names and nets, part order shuffled) for the footprints in the layout excerpt that follows; sources: Cadence DE-HDL packaged netlist, KiCad conversion of Wiwynn_Tioga_Pass_MB.brd

RT42  1R3F-GP  1%  pkg RCL_GP  page 214 : \1\ = VR_PVCCIO_CPU1_PH1_SW_RC ; \2\ = GND
R12W4  RES  100.0K 1% CHIP  pkg 0603  page 197 : A = P12V_NVDIMM_ABC ; B = PWRGD_PVDDQ_ABC_N
C7G29  CAP_A  0.1UF 16V 10% X7R  pkg 0402V  page 216 : A = VR_FET_SW_P12V_STBY_PVDDQ_ABC ; B = GND

(kicad_pcb
	(version 20260206)
	(generator "pcbnew")
	(generator_version "10.0")
	(general
		(thickness 1.6)
		(legacy_teardrops no)
	)
	(paper "A4")
	(title_block
		(title "Wiwynn_Tioga_Pass_MB.brd")
		(comment 1 "Tioga Pass / footprints 2307-2309 of 4770")
	)
	(layers
		(0 "F.Cu" signal "TOP")
		(4 "In1.Cu" signal "L2GND")
		(6 "In2.Cu" signal "L3")
		(8 "In3.Cu" signal "L4GND")
		(10 "In4.Cu" signal "L5")
		(12 "In5.Cu" signal "L6GND")
		(14 "In6.Cu" signal "L7VCC")
		(16 "In7.Cu" signal "L8VCC")
		(18 "In8.Cu" signal "L9GND")
		(20 "In9.Cu" signal "L10")
		(22 "In10.Cu" signal "L11GND")
		(24 "In11.Cu" signal "L12")
		(26 "In12.Cu" signal "L13GND")
		(2 "B.Cu" signal "BOTTOM")
		(9 "F.Adhes" user "F.Adhesive")
		(11 "B.Adhes" user "B.Adhesive")
		(13 "F.Paste" user "Package Geometry/Pastemask Top")
		(15 "B.Paste" user "Package Geometry/Pastemask Bottom")
		(5 "F.SilkS" user "Ref Des/Silkscreen Top")
		(7 "B.SilkS" user "Ref Des/Silkscreen Bottom")
		(1 "F.Mask" user "Board Geometry/Soldermask Top")
		(3 "B.Mask" user "Board Geometry/Soldermask Bottom")
		(17 "Dwgs.User" user "User.Drawings")
		(19 "Cmts.User" user "User.Comments")
		(21 "Eco1.User" user "User.Eco1")
		(23 "Eco2.User" user "User.Eco2")
		(25 "Edge.Cuts" user "Board Geometry/Outline")
		(27 "Margin" user)
		(31 "F.CrtYd" user "Package Geometry/Place Bound Top")
		(29 "B.CrtYd" user "Package Geometry/Place Bound Bottom")
		(35 "F.Fab" user "Ref Des/Assembly Top")
		(33 "B.Fab" user "Ref Des/Assembly Bottom")
	)
	(footprint ""
		(layer "F.Cu")
		(at 173.1264 -57.9374 90)
		(property "Reference" "RT42"
			(at 0 0 90)
			(layer "F.SilkS")
			(hide yes)
			(effects
				(font
					(size 1.27 1.27)
				)
			)
		)
		(property "Value" "*"
			(at -0.0254 -2.6289 90)
			(unlocked yes)
			(layer "F.Fab")
			(hide yes)
			(effects
				(font
					(size 1.27 1.016)
					(thickness 0.1524)
				)
			)
		)
		(property "Device Type" "1R3F-GP_RCL_GP-1R3F-GP,64.1R00A"
			(at -0.0254 -4.1529 90)
			(unlocked yes)
			(layer "F.Fab")
			(hide yes)
			(effects
				(font
					(size 1.27 1.016)
					(thickness 0.1524)
				)
			)
		)
		(duplicate_pad_numbers_are_jumpers no)
		(fp_line
			(start 0.2032 0)
			(end 0.4826 0)
			(stroke
				(width 0.2032)
				(type default)
			)
			(layer "F.SilkS")
		)
		(fp_line
			(start -0.4826 0)
			(end -0.2032 0)
			(stroke
				(width 0.2032)
				(type default)
			)
			(layer "F.SilkS")
		)
		(fp_rect
			(start -0.5842 1.3335)
			(end 0.5842 -1.3335)
			(stroke
				(width 0)
				(type default)
			)
			(fill no)
			(layer "F.CrtYd")
		)
		(fp_rect
			(start -0.5842 1.3335)
			(end 0.5842 -1.3335)
			(stroke
				(width 0)
				(type default)
			)
			(fill no)
			(layer "F.Fab")
		)
		(pad "1" smd custom
			(at 0 -0.762 90)
			(size 0.2159 0.2159)
			(layers "F.Cu" "F.Mask" "F.Paste")
			(net "VR_PVCCIO_CPU1_PH1_SW_RC")
			(options
				(clearance outline)
				(anchor circle)
			)
			(primitives
				(gr_poly
					(pts
						(arc
							(start -0.3302 -0.4318)
							(mid -0.402042 -0.402042)
							(end -0.4318 -0.3302)
						)
						(arc
							(start -0.4318 0.3302)
							(mid -0.402042 0.402042)
							(end -0.3302 0.4318)
						)
						(arc
							(start 0.3302 0.4318)
							(mid 0.402042 0.402042)
							(end 0.4318 0.3302)
						)
						(arc
							(start 0.4318 -0.3302)
							(mid 0.402042 -0.402042)
							(end 0.3302 -0.4318)
						)
					)
					(width 0)
					(fill yes)
				)
			)
		)
		(pad "2" smd custom
			(at 0 0.762 90)
			(size 0.2159 0.2159)
			(layers "F.Cu" "F.Mask" "F.Paste")
			(net "GND")
			(options
				(clearance outline)
				(anchor circle)
			)
			(primitives
				(gr_poly
					(pts
						(arc
							(start -0.3302 -0.4318)
							(mid -0.402042 -0.402042)
							(end -0.4318 -0.3302)
						)
						(arc
							(start -0.4318 0.3302)
							(mid -0.402042 0.402042)
							(end -0.3302 0.4318)
						)
						(arc
							(start 0.3302 0.4318)
							(mid 0.402042 0.402042)
							(end 0.4318 0.3302)
						)
						(arc
							(start 0.4318 -0.3302)
							(mid 0.402042 -0.402042)
							(end 0.3302 -0.4318)
						)
					)
					(width 0)
					(fill yes)
				)
			)
		)
	)
	(footprint ""
		(layer "F.Cu")
		(at 184.428384 -21.34362 -90)
		(property "Reference" "R12W4"
			(at 1.01473 0.656336 180)
			(unlocked yes)
			(layer "F.SilkS")
			(effects
				(font
					(size 0.4064 0.254)
					(thickness 0.1524)
				)
			)
		)
		(property "Value" ""
			(at 0 0 270)
			(layer "F.Fab")
			(effects
				(font
					(size 1.27 1.27)
				)
			)
		)
		(duplicate_pad_numbers_are_jumpers no)
		(fp_poly
			(pts
				(xy -0.4953 -0.2032) (xy 0.4953 -0.2032) (xy 0.4953 1.6002) (xy -0.4953 1.6002)
			)
			(stroke
				(width 0)
				(type default)
			)
			(fill no)
			(layer "F.CrtYd")
		)
		(fp_line
			(start -0.4953 1.6002)
			(end -0.4953 -0.2032)
			(stroke
				(width 0.1)
				(type default)
			)
			(layer "F.Fab")
		)
		(fp_line
			(start 0.4953 1.6002)
			(end -0.4953 1.6002)
			(stroke
				(width 0.1)
				(type default)
			)
			(layer "F.Fab")
		)
		(fp_line
			(start -0.4953 -0.2032)
			(end 0.4953 -0.2032)
			(stroke
				(width 0.1)
				(type default)
			)
			(layer "F.Fab")
		)
		(fp_line
			(start 0.4953 -0.2032)
			(end 0.4953 1.6002)
			(stroke
				(width 0.1)
				(type default)
			)
			(layer "F.Fab")
		)
		(pad "1" smd rect
			(at 0 0 270)
			(size 0.762 0.889)
			(layers "F.Cu" "F.Mask" "F.Paste")
			(net "P12V_NVDIMM_ABC")
		)
		(pad "2" smd rect
			(at 0 1.397 270)
			(size 0.762 0.889)
			(layers "F.Cu" "F.Mask" "F.Paste")
			(net "PWRGD_PVDDQ_ABC_N")
		)
		(zone
			(layer "F.Cu")
			(hatch none 0.5)
			(connect_pads
				(clearance 0)
			)
			(min_thickness 0.25)
			(keepout
				(tracks not_allowed)
				(vias allowed)
				(pads allowed)
				(copperpour not_allowed)
				(footprints allowed)
			)
			(placement
				(enabled no)
				(sheetname "")
			)
			(fill
				(thermal_gap 0.5)
				(thermal_bridge_width 0.5)
				(island_removal_mode 0)
			)
			(polygon
				(pts
					(xy 183.475884 -21.72462) (xy 183.475884 -20.96262) (xy 183.983884 -20.96262) (xy 183.983884 -21.72462)
				)
			)
		)
		(zone
			(layer "F.Cu")
			(hatch none 0.5)
			(connect_pads
				(clearance 0)
			)
			(min_thickness 0.25)
			(keepout
				(tracks allowed)
				(vias not_allowed)
				(pads allowed)
				(copperpour not_allowed)
				(footprints allowed)
			)
			(placement
				(enabled no)
				(sheetname "")
			)
			(fill
				(thermal_gap 0.5)
				(thermal_bridge_width 0.5)
				(island_removal_mode 0)
			)
			(polygon
				(pts
					(xy 183.475884 -20.96262) (xy 183.983884 -20.96262) (xy 183.983884 -21.72462) (xy 183.475884 -21.72462)
				)
			)
		)
	)
	(footprint ""
		(layer "F.Cu")
		(at 347.08719 -2.954782 -90)
		(property "Reference" "C7G29"
			(at 0 0 270)
			(layer "F.SilkS")
			(hide yes)
			(effects
				(font
					(size 1.27 1.27)
				)
			)
		)
		(property "Value" ""
			(at 0 0 270)
			(layer "F.Fab")
			(effects
				(font
					(size 1.27 1.27)
				)
			)
		)
		(duplicate_pad_numbers_are_jumpers no)
		(fp_rect
			(start -0.3048 0.9906)
			(end 0.3048 -0.1016)
			(stroke
				(width 0)
				(type default)
			)
			(fill no)
			(layer "F.CrtYd")
		)
		(fp_line
			(start -0.3048 0.9906)
			(end 0.3048 0.9906)
			(stroke
				(width 0.1)
				(type default)
			)
			(layer "F.Fab")
		)
		(fp_line
			(start 0.3048 0.9906)
			(end 0.3048 -0.1016)
			(stroke
				(width 0.1)
				(type default)
			)
			(layer "F.Fab")
		)
		(fp_line
			(start -0.3048 -0.1016)
			(end -0.3048 0.9906)
			(stroke
				(width 0.1)
				(type default)
			)
			(layer "F.Fab")
		)
		(fp_line
			(start 0.3048 -0.1016)
			(end -0.3048 -0.1016)
			(stroke
				(width 0.1)
				(type default)
			)
			(layer "F.Fab")
		)
		(pad "1" smd rect
			(at 0 0 270)
			(size 0.508 0.508)
			(layers "F.Cu" "F.Mask" "F.Paste")
			(net "VR_FET_SW_P12V_STBY_PVDDQ_ABC")
		)
		(pad "2" smd rect
			(at 0 0.889 270)
			(size 0.508 0.508)
			(layers "F.Cu" "F.Mask" "F.Paste")
			(net "GND")
		)
		(zone
			(layer "F.Cu")
			(hatch none 0.5)
			(connect_pads
				(clearance 0)
			)
			(min_thickness 0.25)
			(keepout
				(tracks allowed)
				(vias not_allowed)
				(pads allowed)
				(copperpour not_allowed)
				(footprints allowed)
			)
			(placement
				(enabled no)
				(sheetname "")
			)
			(fill
				(thermal_gap 0.5)
				(thermal_bridge_width 0.5)
				(island_removal_mode 0)
			)
			(polygon
				(pts
					(xy 346.45219 -3.208782) (xy 346.45219 -2.700782) (xy 346.83319 -2.700782) (xy 346.83319 -3.208782)
				)
			)
		)
		(zone
			(layer "F.Cu")
			(hatch none 0.5)
			(connect_pads
				(clearance 0)
			)
			(min_thickness 0.25)
			(keepout
				(tracks not_allowed)
				(vias allowed)
				(pads allowed)
				(copperpour not_allowed)
				(footprints allowed)
			)
			(placement
				(enabled no)
				(sheetname "")
			)
			(fill
				(thermal_gap 0.5)
				(thermal_bridge_width 0.5)
				(island_removal_mode 0)
			)
			(polygon
				(pts
					(xy 346.45219 -3.208782) (xy 346.45219 -2.700782) (xy 346.83319 -2.700782) (xy 346.83319 -3.208782)
				)
			)
		)
	)
)
